(kicad_pcb
	(version 20240108)
	(generator "pcbnew")
	(generator_version "8.0")
	(general
		(thickness 1.62)
		(legacy_teardrops no)
	)
	(paper "A4")
	(title_block
		(title "Jetson Orin Baseboard")
		(date "2025-03-12")
		(rev "1.3.4")
		(company "Antmicro Ltd")
		(comment 1 "www.antmicro.com")
		(comment 9 "footprints 485-487 of 677")
	)
	(layers
		(0 "F.Cu" signal)
		(1 "In1.Cu" signal)
		(2 "In2.Cu" signal)
		(3 "In3.Cu" signal)
		(4 "In4.Cu" jumper)
		(5 "In5.Cu" signal)
		(6 "In6.Cu" signal)
		(31 "B.Cu" signal)
		(32 "B.Adhes" user "B.Adhesive")
		(33 "F.Adhes" user "F.Adhesive")
		(34 "B.Paste" user)
		(35 "F.Paste" user)
		(36 "B.SilkS" user "B.Silkscreen")
		(37 "F.SilkS" user "F.Silkscreen")
		(38 "B.Mask" user)
		(39 "F.Mask" user)
		(40 "Dwgs.User" user "User.Drawings")
		(41 "Cmts.User" user "User.Comments")
		(42 "Eco1.User" user "User.Eco1")
		(43 "Eco2.User" user "User.Eco2")
		(44 "Edge.Cuts" user)
		(45 "Margin" user)
		(46 "B.CrtYd" user "B.Courtyard")
		(47 "F.CrtYd" user "F.Courtyard")
		(48 "B.Fab" user)
		(49 "F.Fab" user)
	)
	(footprint "antmicro-footprints:QFN-16-1EP_4x4mm_P0.65mm"
		(layer "B.Cu")
		(at 53.4 113.25 180)
		(property "Reference" "U5"
			(at -1.47 2.6 0)
			(layer "B.SilkS")
			(effects
				(font
					(size 0.7 0.7)
					(thickness 0.15)
				)
				(justify left bottom mirror)
			)
		)
		(property "Value" "FT230X_QFN"
			(at 0 -3.3 0)
			(layer "B.Fab")
			(effects
				(font
					(size 0.7 0.7)
					(thickness 0.15)
				)
				(justify left bottom mirror)
			)
		)
		(property "Footprint" "antmicro-footprints:QFN-16-1EP_4x4mm_P0.65mm"
			(at 0 0 180)
			(layer "F.Fab")
			(hide yes)
			(effects
				(font
					(size 1.27 1.27)
					(thickness 0.15)
				)
			)
		)
		(property "Datasheet" "https://ftdichip.com/wp-content/uploads/2021/10/DS_FT230X.pdf"
			(at 0 0 180)
			(layer "F.Fab")
			(hide yes)
			(effects
				(font
					(size 1.27 1.27)
					(thickness 0.15)
				)
			)
		)
		(property "Author" "Antmicro"
			(at 106.8 226.5 0)
			(layer "B.Fab")
			(hide yes)
			(effects
				(font
					(size 1 1)
					(thickness 0.15)
				)
				(justify mirror)
			)
		)
		(property "License" "Apache-2.0"
			(at 106.8 226.5 0)
			(layer "B.Fab")
			(hide yes)
			(effects
				(font
					(size 1 1)
					(thickness 0.15)
				)
				(justify mirror)
			)
		)
		(property "MPN" "FT230XQ-R"
			(at 106.8 226.5 0)
			(layer "B.Fab")
			(hide yes)
			(effects
				(font
					(size 1 1)
					(thickness 0.15)
				)
				(justify mirror)
			)
		)
		(property "Manufacturer" "FTDI Chip"
			(at 106.8 226.5 0)
			(layer "B.Fab")
			(hide yes)
			(effects
				(font
					(size 1 1)
					(thickness 0.15)
				)
				(justify mirror)
			)
		)
		(sheetname "USB Debug, DP")
		(sheetfile "usb.kicad_sch")
		(attr smd)
		(fp_line
			(start 2.1 2.101)
			(end 1.499 2.101)
			(stroke
				(width 0.15)
				(type solid)
			)
			(layer "B.SilkS")
		)
		(fp_line
			(start 2.1 1.401)
			(end 2.1 2.101)
			(stroke
				(width 0.15)
				(type solid)
			)
			(layer "B.SilkS")
		)
		(fp_line
			(start 2.1 -1.398)
			(end 2.1 -2.1)
			(stroke
				(width 0.15)
				(type solid)
			)
			(layer "B.SilkS")
		)
		(fp_line
			(start 2.1 -2.1)
			(end 1.499 -2.1)
			(stroke
				(width 0.15)
				(type solid)
			)
			(layer "B.SilkS")
		)
		(fp_line
			(start -1.5 -2.1)
			(end -2.101 -2.1)
			(stroke
				(width 0.15)
				(type solid)
			)
			(layer "B.SilkS")
		)
		(fp_line
			(start -2.1 2.1)
			(end -1.4 2.1)
			(stroke
				(width 0.15)
				(type solid)
			)
			(layer "B.SilkS")
		)
		(fp_line
			(start -2.101 1.4)
			(end -2.1 2.1)
			(stroke
				(width 0.15)
				(type solid)
			)
			(layer "B.SilkS")
		)
		(fp_line
			(start -2.101 -2.1)
			(end -2.101 -1.398)
			(stroke
				(width 0.15)
				(type solid)
			)
			(layer "B.SilkS")
		)
		(fp_circle
			(center -2.35 1.4)
			(end -2.3 1.4)
			(stroke
				(width 0.15)
				(type solid)
			)
			(fill solid)
			(layer "B.SilkS")
		)
		(fp_rect
			(start -2.35 2.35)
			(end 2.35 -2.35)
			(stroke
				(width 0.05)
				(type solid)
			)
			(fill none)
			(layer "B.CrtYd")
		)
		(fp_line
			(start -2 1.5)
			(end -1.5 2)
			(stroke
				(width 0.15)
				(type solid)
			)
			(layer "B.Fab")
		)
		(fp_rect
			(start 2 -2)
			(end -2 2)
			(stroke
				(width 0.15)
				(type solid)
			)
			(fill none)
			(layer "B.Fab")
		)
		(fp_text user "Author: Antmicro"
			(at -2.35 -6.799 0)
			(layer "B.Fab")
			(hide yes)
			(effects
				(font
					(size 0.7 0.7)
					(thickness 0.15)
				)
				(justify left bottom mirror)
			)
		)
		(fp_text user "License: Apache-2.0"
			(at -2.35 -7.999 0)
			(layer "B.Fab")
			(hide yes)
			(effects
				(font
					(size 0.7 0.7)
					(thickness 0.15)
				)
				(justify left bottom mirror)
			)
		)
		(fp_text user "${REFERENCE}"
			(at -2.35 -5.599 0)
			(layer "B.Fab")
			(hide yes)
			(effects
				(font
					(size 0.7 0.7)
					(thickness 0.15)
				)
				(justify left bottom mirror)
			)
		)
		(pad "1" smd rect
			(at -1.9 0.975 180)
			(size 0.8 0.4)
			(layers "B.Cu" "B.Paste" "B.Mask")
			(net 185 "/USB Debug, DP/FTDI_3V3")
			(pinfunction "V_{CCIO}")
			(pintype "power_in")
		)
		(pad "2" smd rect
			(at -1.9 0.325 180)
			(size 0.8 0.4)
			(layers "B.Cu" "B.Paste" "B.Mask")
			(net 647 "Net-(U5-RXD)")
			(pinfunction "RXD")
			(pintype "input")
		)
		(pad "3" smd rect
			(at -1.9 -0.325 180)
			(size 0.8 0.4)
			(layers "B.Cu" "B.Paste" "B.Mask")
			(net 1 "GND")
			(pinfunction "GND")
			(pintype "passive")
		)
		(pad "4" smd rect
			(at -1.9 -0.975 180)
			(size 0.8 0.4)
			(layers "B.Cu" "B.Paste" "B.Mask")
			(net 649 "Net-(U5-~{CTS})")
			(pinfunction "~{CTS}")
			(pintype "input")
		)
		(pad "5" smd rect
			(at -0.975 -1.9 180)
			(size 0.4 0.8)
			(layers "B.Cu" "B.Paste" "B.Mask")
			(net 271 "/USB Debug, DP/FTDI_LED_TX")
			(pinfunction "CBUS2")
			(pintype "bidirectional")
		)
		(pad "6" smd rect
			(at -0.325 -1.9 180)
			(size 0.4 0.8)
			(layers "B.Cu" "B.Paste" "B.Mask")
			(net 313 "/USB Debug, DP/USB_FTDI_P")
			(pinfunction "D+")
			(pintype "input")
		)
		(pad "7" smd rect
			(at 0.325 -1.9 180)
			(size 0.4 0.8)
			(layers "B.Cu" "B.Paste" "B.Mask")
			(net 312 "/USB Debug, DP/USB_FTDI_N")
			(pinfunction "D-")
			(pintype "input")
		)
		(pad "8" smd rect
			(at 0.975 -1.9 180)
			(size 0.4 0.8)
			(layers "B.Cu" "B.Paste" "B.Mask")
			(net 185 "/USB Debug, DP/FTDI_3V3")
			(pinfunction "3V3_{OUT}")
			(pintype "passive")
		)
		(pad "9" smd rect
			(at 1.9 -0.975 180)
			(size 0.8 0.4)
			(layers "B.Cu" "B.Paste" "B.Mask")
			(net 126 "Net-(U5-~{RESET})")
			(pinfunction "~{RESET}")
			(pintype "input")
		)
		(pad "10" smd rect
			(at 1.9 -0.325 180)
			(size 0.8 0.4)
			(layers "B.Cu" "B.Paste" "B.Mask")
			(net 185 "/USB Debug, DP/FTDI_3V3")
			(pinfunction "V_{CC}")
			(pintype "power_in")
		)
		(pad "11" smd rect
			(at 1.9 0.325 180)
			(size 0.8 0.4)
			(layers "B.Cu" "B.Paste" "B.Mask")
			(net 272 "/USB Debug, DP/FTDI_LED_RX")
			(pinfunction "CBUS1")
			(pintype "bidirectional")
		)
		(pad "12" smd rect
			(at 1.9 0.975 180)
			(size 0.8 0.4)
			(layers "B.Cu" "B.Paste" "B.Mask")
			(net 780 "/USB Debug, DP/FTDI_CBUS0{slash}SDA")
			(pinfunction "CBUS0")
			(pintype "bidirectional")
		)
		(pad "13" smd rect
			(at 0.975 1.9 180)
			(size 0.4 0.8)
			(layers "B.Cu" "B.Paste" "B.Mask")
			(net 1 "GND")
			(pinfunction "GND")
			(pintype "power_in")
		)
		(pad "14" smd rect
			(at 0.325 1.9 180)
			(size 0.4 0.8)
			(layers "B.Cu" "B.Paste" "B.Mask")
			(net 398 "/USB Debug, DP/FTDI_CBUS3{slash}SCL")
			(pinfunction "CBUS3")
			(pintype "bidirectional")
		)
		(pad "15" smd rect
			(at -0.325 1.9 180)
			(size 0.4 0.8)
			(layers "B.Cu" "B.Paste" "B.Mask")
			(net 646 "Net-(U5-TXD)")
			(pinfunction "TXD")
			(pintype "output")
		)
		(pad "16" smd rect
			(at -0.975 1.9 180)
			(size 0.4 0.8)
			(layers "B.Cu" "B.Paste" "B.Mask")
			(net 648 "Net-(U5-~{RTS})")
			(pinfunction "~{RTS}")
			(pintype "output")
		)
		(pad "17" smd rect
			(at 0 0 180)
			(size 2.3 2.3)
			(layers "B.Cu" "B.Paste" "B.Mask")
			(net 1 "GND")
			(pinfunction "GND")
			(pintype "passive")
		)
	)
	(footprint "antmicro-footprints:SOT-23-3"
		(layer "B.Cu")
		(at 58.885627 92.05 -90)
		(property "Reference" "Q6"
			(at 1.545339 -1.864373 0)
			(layer "B.SilkS")
			(effects
				(font
					(size 0.7 0.7)
					(thickness 0.15)
				)
				(justify left top mirror)
			)
		)
		(property "Value" "SSM3J332R"
			(at -1.9 -2.7 90)
			(layer "B.Fab")
			(effects
				(font
					(size 0.7 0.7)
					(thickness 0.15)
				)
				(justify left top mirror)
			)
		)
		(property "Footprint" "antmicro-footprints:SOT-23-3"
			(at 0 0 90)
			(layer "B.Fab")
			(hide yes)
			(effects
				(font
					(size 1.27 1.27)
					(thickness 0.15)
				)
				(justify mirror)
			)
		)
		(property "Datasheet" "https://www.mouser.com/datasheet/2/408/SSM3J332R_datasheet_en_20181015-1150575.pdf"
			(at 0 0 90)
			(layer "B.Fab")
			(hide yes)
			(effects
				(font
					(size 1.27 1.27)
					(thickness 0.15)
				)
				(justify mirror)
			)
		)
		(property "MPN" "SSM3J332R,LF"
			(at 0 0 -90)
			(unlocked yes)
			(layer "B.Fab")
			(hide yes)
			(effects
				(font
					(size 1 1)
					(thickness 0.15)
				)
				(justify mirror)
			)
		)
		(property "Manufacturer" "Toshiba"
			(at 0 0 -90)
			(unlocked yes)
			(layer "B.Fab")
			(hide yes)
			(effects
				(font
					(size 1 1)
					(thickness 0.15)
				)
				(justify mirror)
			)
		)
		(property "Author" "Antmicro"
			(at 0 0 -90)
			(unlocked yes)
			(layer "B.Fab")
			(hide yes)
			(effects
				(font
					(size 1 1)
					(thickness 0.15)
				)
				(justify mirror)
			)
		)
		(property "License" "Apache-2.0"
			(at 0 0 -90)
			(unlocked yes)
			(layer "B.Fab")
			(hide yes)
			(effects
				(font
					(size 1 1)
					(thickness 0.15)
				)
				(justify mirror)
			)
		)
		(sheetname "Supply")
		(sheetfile "supply.kicad_sch")
		(attr smd)
		(fp_line
			(start -0.7 1.5)
			(end 0.7 1.5)
			(stroke
				(width 0.15)
				(type solid)
			)
			(layer "B.SilkS")
		)
		(fp_line
			(start -0.7 1.5)
			(end -0.85 1.35)
			(stroke
				(width 0.15)
				(type solid)
			)
			(layer "B.SilkS")
		)
		(fp_line
			(start 0.7 1.5)
			(end 0.7 0.4)
			(stroke
				(width 0.15)
				(type solid)
			)
			(layer "B.SilkS")
		)
		(fp_line
			(start -0.85 1.35)
			(end -1.45 1.35)
			(stroke
				(width 0.15)
				(type solid)
			)
			(layer "B.SilkS")
		)
		(fp_line
			(start -0.7 -1.35)
			(end -0.7 -1.5)
			(stroke
				(width 0.15)
				(type solid)
			)
			(layer "B.SilkS")
		)
		(fp_line
			(start -0.7 -1.5)
			(end 0.7 -1.5)
			(stroke
				(width 0.15)
				(type solid)
			)
			(layer "B.SilkS")
		)
		(fp_line
			(start 0.7 -1.5)
			(end 0.7 -0.4)
			(stroke
				(width 0.15)
				(type solid)
			)
			(layer "B.SilkS")
		)
		(fp_line
			(start 0.825 1.6)
			(end -0.9 1.6)
			(stroke
				(width 0.05)
				(type solid)
			)
			(layer "B.CrtYd")
		)
		(fp_line
			(start -1.75 1.4)
			(end -0.9 1.4)
			(stroke
				(width 0.05)
				(type solid)
			)
			(layer "B.CrtYd")
		)
		(fp_line
			(start -1.75 1.4)
			(end -1.75 0.5)
			(stroke
				(width 0.05)
				(type solid)
			)
			(layer "B.CrtYd")
		)
		(fp_line
			(start -0.9 1.4)
			(end -0.9 1.6)
			(stroke
				(width 0.05)
				(type solid)
			)
			(layer "B.CrtYd")
		)
		(fp_line
			(start -1.75 0.5)
			(end -0.85 0.5)
			(stroke
				(width 0.05)
				(type solid)
			)
			(layer "B.CrtYd")
		)
		(fp_line
			(start -0.85 0.5)
			(end -0.85 -0.5)
			(stroke
				(width 0.05)
				(type solid)
			)
			(layer "B.CrtYd")
		)
		(fp_line
			(start 0.825 0.45)
			(end 0.825 1.6)
			(stroke
				(width 0.05)
				(type solid)
			)
			(layer "B.CrtYd")
		)
		(fp_line
			(start 1.75 0.45)
			(end 0.825 0.45)
			(stroke
				(width 0.05)
				(type solid)
			)
			(layer "B.CrtYd")
		)
		(fp_line
			(start 0.85 -0.45)
			(end 1.75 -0.45)
			(stroke
				(width 0.05)
				(type solid)
			)
			(layer "B.CrtYd")
		)
		(fp_line
			(start 1.75 -0.45)
			(end 1.75 0.45)
			(stroke
				(width 0.05)
				(type solid)
			)
			(layer "B.CrtYd")
		)
		(fp_line
			(start -1.75 -0.5)
			(end -1.75 -1.4)
			(stroke
				(width 0.05)
				(type solid)
			)
			(layer "B.CrtYd")
		)
		(fp_line
			(start -0.85 -0.5)
			(end -1.75 -0.5)
			(stroke
				(width 0.05)
				(type solid)
			)
			(layer "B.CrtYd")
		)
		(fp_line
			(start -1.75 -1.4)
			(end -0.85 -1.4)
			(stroke
				(width 0.05)
				(type solid)
			)
			(layer "B.CrtYd")
		)
		(fp_line
			(start -0.85 -1.4)
			(end -0.85 -1.65)
			(stroke
				(width 0.05)
				(type solid)
			)
			(layer "B.CrtYd")
		)
		(fp_line
			(start -0.85 -1.65)
			(end 0.85 -1.65)
			(stroke
				(width 0.05)
				(type solid)
			)
			(layer "B.CrtYd")
		)
		(fp_line
			(start 0.85 -1.65)
			(end 0.85 -0.45)
			(stroke
				(width 0.05)
				(type solid)
			)
			(layer "B.CrtYd")
		)
		(fp_line
			(start 0.688 1.526)
			(end -0.437 1.526)
			(stroke
				(width 0.15)
				(type solid)
			)
			(layer "B.Fab")
		)
		(fp_line
			(start 0.688 1.52)
			(end 0.688 -1.519)
			(stroke
				(width 0.15)
				(type solid)
			)
			(layer "B.Fab")
		)
		(fp_line
			(start -0.712 1.325)
			(end -0.437 1.526)
			(stroke
				(width 0.15)
				(type solid)
			)
			(layer "B.Fab")
		)
		(fp_line
			(start 0.688 -1.519)
			(end -0.712 -1.519)
			(stroke
				(width 0.15)
				(type solid)
			)
			(layer "B.Fab")
		)
		(fp_line
			(start -0.712 -1.523)
			(end -0.712 1.325)
			(stroke
				(width 0.15)
				(type solid)
			)
			(layer "B.Fab")
		)
		(fp_text user "License: Apache-2.0"
			(at -1.8 -6.8 90)
			(layer "B.Fab")
			(hide yes)
			(effects
				(font
					(size 0.7 0.7)
					(thickness 0.15)
				)
				(justify left top mirror)
			)
		)
		(fp_text user "Author: Antmicro"
			(at -1.837 -5.3 90)
			(layer "B.Fab")
			(hide yes)
			(effects
				(font
					(size 0.7 0.7)
					(thickness 0.15)
				)
				(justify left top mirror)
			)
		)
		(fp_text user "${REFERENCE}"
			(at -1.837 -4 90)
			(layer "B.Fab")
			(hide yes)
			(effects
				(font
					(size 0.7 0.7)
					(thickness 0.15)
				)
				(justify left top mirror)
			)
		)
		(pad "1" smd roundrect
			(at -1.1 0.951 270)
			(size 1 0.6)
			(layers "B.Cu" "B.Paste" "B.Mask")
			(roundrect_rratio 0.15)
			(net 768 "/Supply/5V_GATE")
			(pinfunction "G")
			(pintype "bidirectional")
		)
		(pad "2" smd roundrect
			(at -1.1 -0.949 270)
			(size 1 0.6)
			(layers "B.Cu" "B.Paste" "B.Mask")
			(roundrect_rratio 0.15)
			(net 787 "+5V_SoM")
			(pinfunction "S")
			(pintype "bidirectional")
		)
		(pad "3" smd roundrect
			(at 1.1 0.0005 270)
			(size 1 0.6)
			(layers "B.Cu" "B.Paste" "B.Mask")
			(roundrect_rratio 0.15)
			(net 99 "+5V")
			(pinfunction "D")
			(pintype "bidirectional")
		)
	)
	(footprint "antmicro-footprints:R_0402_1005Metric"
		(layer "B.Cu")
		(at 87 112.6 90)
		(descr "Resistor SMD 0402")
		(tags "resistor SMD 0402")
		(property "Reference" "R215"
			(at 0.965 -3.6 -90)
			(layer "B.SilkS")
			(effects
				(font
					(size 0.7 0.7)
					(thickness 0.15)
				)
				(justify left bottom mirror)
			)
		)
		(property "Value" "R_0R_0402"
			(at 0 -1.4 -90)
			(layer "B.Fab")
			(effects
				(font
					(size 0.7 0.7)
					(thickness 0.15)
				)
				(justify left bottom mirror)
			)
		)
		(property "Footprint" "antmicro-footprints:R_0402_1005Metric"
			(at 0 0 90)
			(layer "F.Fab")
			(hide yes)
			(effects
				(font
					(size 1.27 1.27)
					(thickness 0.15)
				)
			)
		)
		(property "Datasheet" "https://industrial.panasonic.com/cdbs/www-data/pdf/RDA0000/AOA0000C301.pdf"
			(at 0 0 90)
			(layer "F.Fab")
			(hide yes)
			(effects
				(font
					(size 1.27 1.27)
					(thickness 0.15)
				)
			)
		)
		(property "Author" "Antmicro"
			(at 199.6 25.6 0)
			(layer "B.Fab")
			(hide yes)
			(effects
				(font
					(size 1 1)
					(thickness 0.15)
				)
				(justify mirror)
			)
		)
		(property "Current" "1A"
			(at 199.6 25.6 0)
			(layer "B.Fab")
			(hide yes)
			(effects
				(font
					(size 1 1)
					(thickness 0.15)
				)
				(justify mirror)
			)
		)
		(property "License" "Apache-2.0"
			(at 199.6 25.6 0)
			(layer "B.Fab")
			(hide yes)
			(effects
				(font
					(size 1 1)
					(thickness 0.15)
				)
				(justify mirror)
			)
		)
		(property "MPN" "ERJ2GE0R00X"
			(at 199.6 25.6 0)
			(layer "B.Fab")
			(hide yes)
			(effects
				(font
					(size 1 1)
					(thickness 0.15)
				)
				(justify mirror)
			)
		)
		(property "Manufacturer" "Panasonic"
			(at 199.6 25.6 0)
			(layer "B.Fab")
			(hide yes)
			(effects
				(font
					(size 1 1)
					(thickness 0.15)
				)
				(justify mirror)
			)
		)
		(property "Tolerance" ""
			(at 199.6 25.6 0)
			(layer "B.Fab")
			(hide yes)
			(effects
				(font
					(size 1 1)
					(thickness 0.15)
				)
				(justify mirror)
			)
		)
		(property "Val" "0R"
			(at 199.6 25.6 0)
			(layer "B.Fab")
			(hide yes)
			(effects
				(font
					(size 1 1)
					(thickness 0.15)
				)
				(justify mirror)
			)
		)
		(sheetname "Peripherals")
		(sheetfile "peripherals.kicad_sch")
		(attr smd)
		(fp_rect
			(start -0.925 0.47)
			(end 0.925 -0.47)
			(stroke
				(width 0.05)
				(type default)
			)
			(fill none)
			(layer "B.CrtYd")
		)
		(fp_rect
			(start -0.5 0.25)
			(end 0.5 -0.25)
			(stroke
				(width 0.15)
				(type solid)
			)
			(fill none)
			(layer "B.Fab")
		)
		(fp_text user "License: Apache-2.0"
			(at -0.95 -5.169 -90)
			(layer "B.Fab")
			(hide yes)
			(effects
				(font
					(size 0.7 0.7)
					(thickness 0.15)
				)
				(justify left bottom mirror)
			)
		)
		(fp_text user "${REFERENCE}"
			(at -0.95 -3.168 -90)
			(layer "B.Fab")
			(hide yes)
			(effects
				(font
					(size 0.7 0.7)
					(thickness 0.15)
				)
				(justify left bottom mirror)
			)
		)
		(fp_text user "Author: Antmicro"
			(at -0.95 -4.169 -90)
			(layer "B.Fab")
			(hide yes)
			(effects
				(font
					(size 0.7 0.7)
					(thickness 0.15)
				)
				(justify left bottom mirror)
			)
		)
		(pad "1" smd roundrect
			(at -0.48 0 90)
			(size 0.59 0.64)
			(layers "B.Cu" "B.Paste" "B.Mask")
			(roundrect_rratio 0.25)
			(net 251 "SYS_SDA")
			(pintype "passive")
		)
		(pad "2" smd roundrect
			(at 0.48 0 90)
			(size 0.59 0.64)
			(layers "B.Cu" "B.Paste" "B.Mask")
			(roundrect_rratio 0.25)
			(net 349 "/Peripherals/GPIOEX_I2C_SDA")
			(pintype "passive")
		)
	)
)
